(kicad_pcb
	(version 20260206)
	(generator "pcbnew")
	(generator_version "10.0")
	(general
		(thickness 1.6)
		(legacy_teardrops no)
	)
	(paper "A4")
	(title_block
		(title "ptb — Lightning_PTB_BRD.brd")
		(comment 1 "Lightning (Wiwynn / Facebook NVMe JBOF) / footprints 43-50 of 61")
	)
	(layers
		(0 "F.Cu" signal "TOP")
		(4 "In1.Cu" signal "L2GND")
		(6 "In2.Cu" signal "L3VCC")
		(2 "B.Cu" signal "BOTTOM")
		(9 "F.Adhes" user "F.Adhesive")
		(11 "B.Adhes" user "B.Adhesive")
		(13 "F.Paste" user "Package Geometry/Pastemask Top")
		(15 "B.Paste" user "Package Geometry/Pastemask Bottom")
		(5 "F.SilkS" user "Ref Des/Silkscreen Top")
		(7 "B.SilkS" user "Ref Des/Silkscreen Bottom")
		(1 "F.Mask" user "Board Geometry/Soldermask Top")
		(3 "B.Mask" user "Board Geometry/Soldermask Bottom")
		(17 "Dwgs.User" user "User.Drawings")
		(19 "Cmts.User" user "User.Comments")
		(21 "Eco1.User" user "User.Eco1")
		(23 "Eco2.User" user "User.Eco2")
		(25 "Edge.Cuts" user "Board Geometry/Outline")
		(27 "Margin" user)
		(31 "F.CrtYd" user "Package Geometry/Place Bound Top")
		(29 "B.CrtYd" user "Package Geometry/Place Bound Bottom")
		(35 "F.Fab" user "Ref Des/Assembly Top")
		(33 "B.Fab" user "Ref Des/Assembly Bottom")
	)
	(footprint ""
		(layer "F.Cu")
		(at 135.111744 -81.813908 90)
		(property "Reference" "R375"
			(at 0 0 90)
			(layer "F.SilkS")
			(hide yes)
			(effects
				(font
					(size 1.27 1.27)
				)
			)
		)
		(property "Value" "100R2F-L1-GP-U"
			(at 0.064008 -3.993896 90)
			(unlocked yes)
			(layer "F.Fab")
			(hide yes)
			(effects
				(font
					(size 1.016 1.016)
					(thickness 0.1524)
				)
			)
		)
		(property "Device Type" "R402H14"
			(at 0.064008 -5.517896 90)
			(unlocked yes)
			(layer "F.Fab")
			(hide yes)
			(effects
				(font
					(size 1.016 1.016)
					(thickness 0.1524)
				)
			)
		)
		(duplicate_pad_numbers_are_jumpers no)
		(fp_line
			(start 0.508 -0.9398)
			(end -0.508 -0.9398)
			(stroke
				(width 0.1524)
				(type default)
			)
			(layer "F.SilkS")
		)
		(fp_line
			(start -0.508 -0.9398)
			(end -0.508 0.9398)
			(stroke
				(width 0.1524)
				(type default)
			)
			(layer "F.SilkS")
		)
		(fp_rect
			(start -0.508 0.9398)
			(end 0.508 -0.9398)
			(stroke
				(width 0)
				(type default)
			)
			(fill no)
			(layer "F.CrtYd")
		)
		(fp_rect
			(start -0.508 0.9398)
			(end 0.508 -0.9398)
			(stroke
				(width 0)
				(type default)
			)
			(fill no)
			(layer "F.Fab")
		)
		(pad "1" smd custom
			(at 0 -0.4445 90)
			(size 0.1397 0.1397)
			(layers "F.Cu" "F.Mask" "F.Paste")
			(net "TRAY PRESENT_OUT_NET")
			(options
				(clearance outline)
				(anchor circle)
			)
			(primitives
				(gr_poly
					(pts
						(arc
							(start -0.1778 -0.2794)
							(mid -0.249642 -0.249642)
							(end -0.2794 -0.1778)
						)
						(arc
							(start -0.2794 0.1778)
							(mid -0.249642 0.249642)
							(end -0.1778 0.2794)
						)
						(arc
							(start 0.1778 0.2794)
							(mid 0.249642 0.249642)
							(end 0.2794 0.1778)
						)
						(arc
							(start 0.2794 -0.1778)
							(mid 0.249642 -0.249642)
							(end 0.1778 -0.2794)
						)
					)
					(width 0)
					(fill yes)
				)
			)
		)
		(pad "2" smd custom
			(at 0 0.4445 90)
			(size 0.1397 0.1397)
			(layers "F.Cu" "F.Mask" "F.Paste")
			(net "TRAY_PRESENT_OUT_NET_B")
			(options
				(clearance outline)
				(anchor circle)
			)
			(primitives
				(gr_poly
					(pts
						(arc
							(start -0.1778 -0.2794)
							(mid -0.249642 -0.249642)
							(end -0.2794 -0.1778)
						)
						(arc
							(start -0.2794 0.1778)
							(mid -0.249642 0.249642)
							(end -0.1778 0.2794)
						)
						(arc
							(start 0.1778 0.2794)
							(mid 0.249642 0.249642)
							(end 0.2794 0.1778)
						)
						(arc
							(start 0.2794 -0.1778)
							(mid 0.249642 -0.249642)
							(end 0.1778 -0.2794)
						)
					)
					(width 0)
					(fill yes)
				)
			)
		)
	)
	(footprint ""
		(layer "F.Cu")
		(at 117.348 -47.371 180)
		(property "Reference" "C361"
			(at 0 0 180)
			(layer "F.SilkS")
			(hide yes)
			(effects
				(font
					(size 1.27 1.27)
				)
			)
		)
		(property "Value" "SC47U16V0MX-GP"
			(at -0.00254 -4.78536 180)
			(unlocked yes)
			(layer "F.Fab")
			(hide yes)
			(effects
				(font
					(size 1.016 1.016)
					(thickness 0.1524)
				)
			)
		)
		(property "Device Type" "C1210H107"
			(at -0.00254 -6.38048 180)
			(unlocked yes)
			(layer "F.Fab")
			(hide yes)
			(effects
				(font
					(size 1.016 1.016)
					(thickness 0.1524)
				)
			)
		)
		(duplicate_pad_numbers_are_jumpers no)
		(fp_line
			(start 1.5748 2.3368)
			(end 1.5748 0.762)
			(stroke
				(width 0.1524)
				(type default)
			)
			(layer "F.SilkS")
		)
		(fp_line
			(start 1.5748 -0.762)
			(end 1.5748 -2.3368)
			(stroke
				(width 0.1524)
				(type default)
			)
			(layer "F.SilkS")
		)
		(fp_line
			(start 1.5748 -2.3368)
			(end -1.5748 -2.3368)
			(stroke
				(width 0.1524)
				(type default)
			)
			(layer "F.SilkS")
		)
		(fp_line
			(start -1.5748 2.3368)
			(end 1.5748 2.3368)
			(stroke
				(width 0.1524)
				(type default)
			)
			(layer "F.SilkS")
		)
		(fp_line
			(start -1.5748 0.762)
			(end -1.5748 2.3368)
			(stroke
				(width 0.1524)
				(type default)
			)
			(layer "F.SilkS")
		)
		(fp_line
			(start -1.5748 -2.3368)
			(end -1.5748 -0.762)
			(stroke
				(width 0.1524)
				(type default)
			)
			(layer "F.SilkS")
		)
		(fp_rect
			(start -1.651 2.413)
			(end 1.651 -2.413)
			(stroke
				(width 0)
				(type default)
			)
			(fill no)
			(layer "F.CrtYd")
		)
		(fp_poly
			(pts
				(xy 1.651 2.413) (xy 1.651 -2.413) (xy -1.651 -2.413) (xy -1.651 2.413)
			)
			(stroke
				(width 0)
				(type default)
			)
			(fill no)
			(layer "F.Fab")
		)
		(pad "1" smd rect
			(at 0 -1.4732 180)
			(size 2.794 1.397)
			(layers "F.Cu" "F.Mask" "F.Paste")
			(net "P12V")
		)
		(pad "2" smd rect
			(at 0 1.4732 180)
			(size 2.794 1.397)
			(layers "F.Cu" "F.Mask" "F.Paste")
			(net "GND")
		)
	)
	(footprint ""
		(layer "F.Cu")
		(at 131.659884 -113.999772)
		(property "Reference" "H1"
			(at 0 0 0)
			(layer "F.SilkS")
			(hide yes)
			(effects
				(font
					(size 1.27 1.27)
				)
			)
		)
		(property "Value" "HOLE"
			(at -18.200878 0.089916 0)
			(unlocked yes)
			(layer "F.Fab")
			(hide yes)
			(effects
				(font
					(size 1.016 1.016)
					(thickness 0.1524)
				)
			)
		)
		(property "Device Type" "HOLET827X355B355R158-S"
			(at -18.200878 -1.434084 0)
			(unlocked yes)
			(layer "F.Fab")
			(hide yes)
			(effects
				(font
					(size 1.016 1.016)
					(thickness 0.1524)
				)
			)
		)
		(duplicate_pad_numbers_are_jumpers no)
		(fp_poly
			(pts
				(arc
					(start 4.8133 0)
					(mid -4.8133 0)
					(end 4.8133 0)
				)
			)
			(stroke
				(width 0)
				(type default)
			)
			(fill no)
			(layer "B.CrtYd")
		)
		(fp_poly
			(pts
				(arc
					(start -11.9888 4.8133)
					(mid -16.8021 0)
					(end -11.9888 -4.8133)
				)
				(arc
					(start 0 -4.8133)
					(mid 4.8133 0)
					(end 0 4.8133)
				)
			)
			(stroke
				(width 0)
				(type default)
			)
			(fill no)
			(layer "F.CrtYd")
		)
		(fp_poly
			(pts
				(arc
					(start 4.8133 0)
					(mid -4.8133 0)
					(end 4.8133 0)
				)
			)
			(stroke
				(width 0)
				(type default)
			)
			(fill no)
			(layer "B.Fab")
		)
		(fp_poly
			(pts
				(arc
					(start -11.9888 4.8133)
					(mid -16.8021 0)
					(end -11.9888 -4.8133)
				)
				(arc
					(start 0 -4.8133)
					(mid 4.8133 0)
					(end 0 4.8133)
				)
			)
			(stroke
				(width 0)
				(type default)
			)
			(fill no)
			(layer "F.Fab")
		)
		(pad "1" thru_hole oval
			(at 0 0)
			(size 21.0058 9.017)
			(drill 4.0132
				(offset -5.9944 0)
			)
			(layers "*.Cu" "*.Mask")
			(remove_unused_layers no)
			(net "GND")
			(clearance -7.9883)
			(thermal_gap 0.3048)
			(padstack
				(mode front_inner_back)
				(layer "Inner"
					(shape circle)
					(size 4.4196 4.4196)
					(clearance 0.3048)
				)
				(layer "B.Cu"
					(shape circle)
					(size 9.017 9.017)
					(clearance -1.9939)
				)
			)
		)
	)
	(footprint ""
		(layer "F.Cu")
		(at 17.220692 -93.84538 90)
		(property "Reference" "R480"
			(at 0 0 90)
			(layer "F.SilkS")
			(hide yes)
			(effects
				(font
					(size 1.27 1.27)
				)
			)
		)
		(property "Value" "0R2J-2-GP"
			(at 0.064008 -3.993896 90)
			(unlocked yes)
			(layer "F.Fab")
			(hide yes)
			(effects
				(font
					(size 1.016 1.016)
					(thickness 0.1524)
				)
			)
		)
		(property "Device Type" "R402H16"
			(at 0.064008 -5.517896 90)
			(unlocked yes)
			(layer "F.Fab")
			(hide yes)
			(effects
				(font
					(size 1.016 1.016)
					(thickness 0.1524)
				)
			)
		)
		(duplicate_pad_numbers_are_jumpers no)
		(fp_line
			(start 0.508 -0.9398)
			(end -0.508 -0.9398)
			(stroke
				(width 0.1524)
				(type default)
			)
			(layer "F.SilkS")
		)
		(fp_line
			(start -0.508 -0.9398)
			(end -0.508 0.9398)
			(stroke
				(width 0.1524)
				(type default)
			)
			(layer "F.SilkS")
		)
		(fp_rect
			(start -0.508 0.9398)
			(end 0.508 -0.9398)
			(stroke
				(width 0)
				(type default)
			)
			(fill no)
			(layer "F.CrtYd")
		)
		(fp_rect
			(start -0.508 0.9398)
			(end 0.508 -0.9398)
			(stroke
				(width 0)
				(type default)
			)
			(fill no)
			(layer "F.Fab")
		)
		(pad "1" smd custom
			(at 0 -0.4445 90)
			(size 0.1397 0.1397)
			(layers "F.Cu" "F.Mask" "F.Paste")
			(net "I2C_C_SCL")
			(options
				(clearance outline)
				(anchor circle)
			)
			(primitives
				(gr_poly
					(pts
						(arc
							(start -0.1778 -0.2794)
							(mid -0.249642 -0.249642)
							(end -0.2794 -0.1778)
						)
						(arc
							(start -0.2794 0.1778)
							(mid -0.249642 0.249642)
							(end -0.1778 0.2794)
						)
						(arc
							(start 0.1778 0.2794)
							(mid 0.249642 0.249642)
							(end 0.2794 0.1778)
						)
						(arc
							(start 0.2794 -0.1778)
							(mid 0.249642 -0.249642)
							(end 0.1778 -0.2794)
						)
					)
					(width 0)
					(fill yes)
				)
			)
		)
		(pad "2" smd custom
			(at 0 0.4445 90)
			(size 0.1397 0.1397)
			(layers "F.Cu" "F.Mask" "F.Paste")
			(net "I2C_C_BUF_SCL")
			(options
				(clearance outline)
				(anchor circle)
			)
			(primitives
				(gr_poly
					(pts
						(arc
							(start -0.1778 -0.2794)
							(mid -0.249642 -0.249642)
							(end -0.2794 -0.1778)
						)
						(arc
							(start -0.2794 0.1778)
							(mid -0.249642 0.249642)
							(end -0.1778 0.2794)
						)
						(arc
							(start 0.1778 0.2794)
							(mid 0.249642 0.249642)
							(end 0.2794 0.1778)
						)
						(arc
							(start 0.2794 -0.1778)
							(mid 0.249642 -0.249642)
							(end 0.1778 -0.2794)
						)
					)
					(width 0)
					(fill yes)
				)
			)
		)
	)
	(footprint ""
		(layer "F.Cu")
		(at 136.652 -74.93)
		(property "Reference" "R379"
			(at 0 0 0)
			(layer "F.SilkS")
			(hide yes)
			(effects
				(font
					(size 1.27 1.27)
				)
			)
		)
		(property "Value" "10KR2F-2-GP"
			(at 0.064008 -3.993896 0)
			(unlocked yes)
			(layer "F.Fab")
			(hide yes)
			(effects
				(font
					(size 1.016 1.016)
					(thickness 0.1524)
				)
			)
		)
		(property "Device Type" "R402H16"
			(at 0.064008 -5.517896 0)
			(unlocked yes)
			(layer "F.Fab")
			(hide yes)
			(effects
				(font
					(size 1.016 1.016)
					(thickness 0.1524)
				)
			)
		)
		(duplicate_pad_numbers_are_jumpers no)
		(fp_line
			(start -0.508 -0.9398)
			(end -0.508 0.9398)
			(stroke
				(width 0.1524)
				(type default)
			)
			(layer "F.SilkS")
		)
		(fp_line
			(start 0.508 -0.9398)
			(end -0.508 -0.9398)
			(stroke
				(width 0.1524)
				(type default)
			)
			(layer "F.SilkS")
		)
		(fp_rect
			(start -0.508 0.9398)
			(end 0.508 -0.9398)
			(stroke
				(width 0)
				(type default)
			)
			(fill no)
			(layer "F.CrtYd")
		)
		(fp_rect
			(start -0.508 0.9398)
			(end 0.508 -0.9398)
			(stroke
				(width 0)
				(type default)
			)
			(fill no)
			(layer "F.Fab")
		)
		(pad "1" smd custom
			(at 0 -0.4445)
			(size 0.1397 0.1397)
			(layers "F.Cu" "F.Mask" "F.Paste")
			(net "P3V3")
			(options
				(clearance outline)
				(anchor circle)
			)
			(primitives
				(gr_poly
					(pts
						(arc
							(start -0.1778 -0.2794)
							(mid -0.249642 -0.249642)
							(end -0.2794 -0.1778)
						)
						(arc
							(start -0.2794 0.1778)
							(mid -0.249642 0.249642)
							(end -0.1778 0.2794)
						)
						(arc
							(start 0.1778 0.2794)
							(mid 0.249642 0.249642)
							(end 0.2794 0.1778)
						)
						(arc
							(start 0.2794 -0.1778)
							(mid 0.249642 -0.249642)
							(end 0.1778 -0.2794)
						)
					)
					(width 0)
					(fill yes)
				)
			)
		)
		(pad "2" smd custom
			(at 0 0.4445)
			(size 0.1397 0.1397)
			(layers "F.Cu" "F.Mask" "F.Paste")
			(net "SELF_TRAY_PRESENT")
			(options
				(clearance outline)
				(anchor circle)
			)
			(primitives
				(gr_poly
					(pts
						(arc
							(start -0.1778 -0.2794)
							(mid -0.249642 -0.249642)
							(end -0.2794 -0.1778)
						)
						(arc
							(start -0.2794 0.1778)
							(mid -0.249642 0.249642)
							(end -0.1778 0.2794)
						)
						(arc
							(start 0.1778 0.2794)
							(mid 0.249642 0.249642)
							(end 0.2794 0.1778)
						)
						(arc
							(start 0.2794 -0.1778)
							(mid 0.249642 -0.249642)
							(end 0.1778 -0.2794)
						)
					)
					(width 0)
					(fill yes)
				)
			)
		)
	)
	(footprint ""
		(layer "F.Cu")
		(at 11.634978 -99.280472 180)
		(property "Reference" "C344"
			(at 0 0 180)
			(layer "F.SilkS")
			(hide yes)
			(effects
				(font
					(size 1.27 1.27)
				)
			)
		)
		(property "Value" "SCD1U50V3KX-GP"
			(at 0 -2.8194 180)
			(unlocked yes)
			(layer "F.Fab")
			(hide yes)
			(effects
				(font
					(size 1.016 1.016)
					(thickness 0.1524)
				)
			)
		)
		(property "Device Type" "C603H36"
			(at 0 -4.3434 180)
			(unlocked yes)
			(layer "F.Fab")
			(hide yes)
			(effects
				(font
					(size 1.016 1.016)
					(thickness 0.1524)
				)
			)
		)
		(duplicate_pad_numbers_are_jumpers no)
		(fp_line
			(start 0.508 0)
			(end -0.508 0)
			(stroke
				(width 0.2032)
				(type default)
			)
			(layer "F.SilkS")
		)
		(fp_rect
			(start -0.5842 1.3335)
			(end 0.5842 -1.3335)
			(stroke
				(width 0)
				(type default)
			)
			(fill no)
			(layer "F.CrtYd")
		)
		(fp_rect
			(start -0.5842 1.3335)
			(end 0.5842 -1.3335)
			(stroke
				(width 0)
				(type default)
			)
			(fill no)
			(layer "F.Fab")
		)
		(pad "1" smd custom
			(at 0 -0.762 180)
			(size 0.2159 0.2159)
			(layers "F.Cu" "F.Mask" "F.Paste")
			(net "P3V3")
			(options
				(clearance outline)
				(anchor circle)
			)
			(primitives
				(gr_poly
					(pts
						(arc
							(start -0.3302 -0.4318)
							(mid -0.402042 -0.402042)
							(end -0.4318 -0.3302)
						)
						(arc
							(start -0.4318 0.3302)
							(mid -0.402042 0.402042)
							(end -0.3302 0.4318)
						)
						(arc
							(start 0.3302 0.4318)
							(mid 0.402042 0.402042)
							(end 0.4318 0.3302)
						)
						(arc
							(start 0.4318 -0.3302)
							(mid 0.402042 -0.402042)
							(end 0.3302 -0.4318)
						)
					)
					(width 0)
					(fill yes)
				)
			)
		)
		(pad "2" smd custom
			(at 0 0.762 180)
			(size 0.2159 0.2159)
			(layers "F.Cu" "F.Mask" "F.Paste")
			(net "GND")
			(options
				(clearance outline)
				(anchor circle)
			)
			(primitives
				(gr_poly
					(pts
						(arc
							(start -0.3302 -0.4318)
							(mid -0.402042 -0.402042)
							(end -0.4318 -0.3302)
						)
						(arc
							(start -0.4318 0.3302)
							(mid -0.402042 0.402042)
							(end -0.3302 0.4318)
						)
						(arc
							(start 0.3302 0.4318)
							(mid 0.402042 0.402042)
							(end 0.4318 0.3302)
						)
						(arc
							(start 0.4318 -0.3302)
							(mid 0.402042 -0.402042)
							(end 0.3302 -0.4318)
						)
					)
					(width 0)
					(fill yes)
				)
			)
		)
	)
	(footprint ""
		(layer "F.Cu")
		(at 156.920692 -103.107744)
		(property "Reference" "PR64"
			(at 0 0 0)
			(layer "F.SilkS")
			(hide yes)
			(effects
				(font
					(size 1.27 1.27)
				)
			)
		)
		(property "Value" "0R3J-0-U-GP"
			(at -0.0254 -2.5146 0)
			(unlocked yes)
			(layer "F.Fab")
			(hide yes)
			(effects
				(font
					(size 1.016 1.016)
					(thickness 0.1524)
				)
			)
		)
		(property "Device Type" "R603H22"
			(at -0.0254 -4.0386 0)
			(unlocked yes)
			(layer "F.Fab")
			(hide yes)
			(effects
				(font
					(size 1.016 1.016)
					(thickness 0.1524)
				)
			)
		)
		(duplicate_pad_numbers_are_jumpers no)
		(fp_line
			(start -0.4826 0)
			(end -0.2032 0)
			(stroke
				(width 0.2032)
				(type default)
			)
			(layer "F.SilkS")
		)
		(fp_line
			(start 0.2032 0)
			(end 0.4826 0)
			(stroke
				(width 0.2032)
				(type default)
			)
			(layer "F.SilkS")
		)
		(fp_rect
			(start -0.5842 1.3335)
			(end 0.5842 -1.3335)
			(stroke
				(width 0)
				(type default)
			)
			(fill no)
			(layer "F.CrtYd")
		)
		(fp_rect
			(start -0.5842 1.3335)
			(end 0.5842 -1.3335)
			(stroke
				(width 0)
				(type default)
			)
			(fill no)
			(layer "F.Fab")
		)
		(pad "1" smd custom
			(at 0 -0.762)
			(size 0.2159 0.2159)
			(layers "F.Cu" "F.Mask" "F.Paste")
			(net "P5VA")
			(options
				(clearance outline)
				(anchor circle)
			)
			(primitives
				(gr_poly
					(pts
						(arc
							(start -0.3302 -0.4318)
							(mid -0.402042 -0.402042)
							(end -0.4318 -0.3302)
						)
						(arc
							(start -0.4318 0.3302)
							(mid -0.402042 0.402042)
							(end -0.3302 0.4318)
						)
						(arc
							(start 0.3302 0.4318)
							(mid 0.402042 0.402042)
							(end 0.4318 0.3302)
						)
						(arc
							(start 0.4318 -0.3302)
							(mid 0.402042 -0.402042)
							(end 0.3302 -0.4318)
						)
					)
					(width 0)
					(fill yes)
				)
			)
		)
		(pad "2" smd custom
			(at 0 0.762)
			(size 0.2159 0.2159)
			(layers "F.Cu" "F.Mask" "F.Paste")
			(net "DETECTOR_C")
			(options
				(clearance outline)
				(anchor circle)
			)
			(primitives
				(gr_poly
					(pts
						(arc
							(start -0.3302 -0.4318)
							(mid -0.402042 -0.402042)
							(end -0.4318 -0.3302)
						)
						(arc
							(start -0.4318 0.3302)
							(mid -0.402042 0.402042)
							(end -0.3302 0.4318)
						)
						(arc
							(start 0.3302 0.4318)
							(mid 0.402042 0.402042)
							(end 0.4318 0.3302)
						)
						(arc
							(start 0.4318 -0.3302)
							(mid 0.402042 -0.402042)
							(end 0.3302 -0.4318)
						)
					)
					(width 0)
					(fill yes)
				)
			)
		)
	)
	(footprint ""
		(layer "F.Cu")
		(at 2.361438 -49.179226 180)
		(property "Reference" "C349"
			(at 0 0 180)
			(layer "F.SilkS")
			(hide yes)
			(effects
				(font
					(size 1.27 1.27)
				)
			)
		)
		(property "Value" "SC10U25V5KX-GP"
			(at -0.0762 -6.1214 180)
			(unlocked yes)
			(layer "F.Fab")
			(hide yes)
			(effects
				(font
					(size 1.016 1.016)
					(thickness 0.1524)
				)
			)
		)
		(property "Device Type" "C805H56"
			(at -0.0762 -8.1534 180)
			(unlocked yes)
			(layer "F.Fab")
			(hide yes)
			(effects
				(font
					(size 1.016 1.016)
					(thickness 0.1524)
				)
			)
		)
		(duplicate_pad_numbers_are_jumpers no)
		(fp_line
			(start 0.635 0)
			(end -0.635 0)
			(stroke
				(width 0.508)
				(type default)
			)
			(layer "F.SilkS")
		)
		(fp_rect
			(start -0.9652 1.778)
			(end 0.9652 -1.778)
			(stroke
				(width 0)
				(type default)
			)
			(fill no)
			(layer "F.CrtYd")
		)
		(fp_poly
			(pts
				(xy -0.9652 -1.778) (xy 0.9652 -1.778) (xy 0.9652 1.778) (xy -0.9652 1.778)
			)
			(stroke
				(width 0)
				(type default)
			)
			(fill no)
			(layer "F.Fab")
		)
		(pad "1" smd rect
			(at 0 -0.9652 180)
			(size 1.397 1.143)
			(layers "F.Cu" "F.Mask" "F.Paste")
			(net "P12V")
		)
		(pad "2" smd rect
			(at 0 0.9652 180)
			(size 1.397 1.143)
			(layers "F.Cu" "F.Mask" "F.Paste")
			(net "GND")
		)
	)
)
